# T6G (Grand Teton) — schematic netlist excerpt (pin names and nets, part order shuffled) for the footprints in the layout excerpt that follows; sources: Cadence DE-HDL packaged netlist, KiCad conversion of 04192023_DAF0TMB3IC0_F0TG_MB_C_brd_V02_OCP.brd

PR103  Q_RES  0 5% CHIP  pkg 0402LF  page 205 : A = PVDDIO_P0_VOS1 ; B = PVDDIO_P0
C169  Q_CAP  10UF 25V 10% X6S  pkg C0805  page 96 : A = P12V_MEM_CPU0 ; B = GND
R542  Q_RES  1K 1% EMPTY  pkg 0402LF  page 55 : A = PVDD11_S3_P1 ; B = I3C_1_SPD_DDRGL_CPU1_R_SCL

(kicad_pcb
	(version 20260206)
	(generator "pcbnew")
	(generator_version "10.0")
	(general
		(thickness 1.6)
		(legacy_teardrops no)
	)
	(paper "A4")
	(title_block
		(title "04192023_DAF0TMB3IC0_F0TG_MB_C_brd_V02_OCP.brd")
		(comment 1 "Grand Teton / footprints 5406-5408 of 8354")
	)
	(layers
		(0 "F.Cu" signal "TOP")
		(4 "In1.Cu" signal "GND")
		(6 "In2.Cu" signal "IN1")
		(8 "In3.Cu" signal "GND1")
		(10 "In4.Cu" signal "IN2")
		(12 "In5.Cu" signal "GND2")
		(14 "In6.Cu" signal "IN3")
		(16 "In7.Cu" signal "GND3")
		(18 "In8.Cu" signal "VCC")
		(20 "In9.Cu" signal "VCC1")
		(22 "In10.Cu" signal "GND4")
		(24 "In11.Cu" signal "IN4")
		(26 "In12.Cu" signal "GND5")
		(28 "In13.Cu" signal "IN5")
		(30 "In14.Cu" signal "GND6")
		(32 "In15.Cu" signal "IN6")
		(34 "In16.Cu" signal "GND7")
		(2 "B.Cu" signal "BOTTOM")
		(9 "F.Adhes" user "F.Adhesive")
		(11 "B.Adhes" user "B.Adhesive")
		(13 "F.Paste" user "Package Geometry/Pastemask Top")
		(15 "B.Paste" user "Package Geometry/Pastemask Bottom")
		(5 "F.SilkS" user "Ref Des/Silkscreen Top")
		(7 "B.SilkS" user "Ref Des/Silkscreen Bottom")
		(1 "F.Mask" user "Board Geometry/Soldermask Top")
		(3 "B.Mask" user "Board Geometry/Soldermask Bottom")
		(17 "Dwgs.User" user "User.Drawings")
		(19 "Cmts.User" user "User.Comments")
		(21 "Eco1.User" user "User.Eco1")
		(23 "Eco2.User" user "User.Eco2")
		(25 "Edge.Cuts" user "Board Geometry/Outline")
		(27 "Margin" user)
		(31 "F.CrtYd" user "Package Geometry/Place Bound Top")
		(29 "B.CrtYd" user "Package Geometry/Place Bound Bottom")
		(35 "F.Fab" user "Ref Des/Assembly Top")
		(33 "B.Fab" user "Ref Des/Assembly Bottom")
	)
	(footprint ""
		(layer "B.Cu")
		(at 296.703496 -349.381572 -90)
		(property "Reference" "PR103"
			(at 0 0 90)
			(layer "B.SilkS")
			(hide yes)
			(effects
				(font
					(size 1.27 1.27)
				)
				(justify mirror)
			)
		)
		(property "Value" ""
			(at 0 0 90)
			(layer "B.Fab")
			(effects
				(font
					(size 1.27 1.27)
				)
				(justify mirror)
			)
		)
		(duplicate_pad_numbers_are_jumpers no)
		(fp_line
			(start -0.7874 0.4064)
			(end 0.7874 0.4064)
			(stroke
				(width 0.1524)
				(type default)
			)
			(layer "B.SilkS")
		)
		(fp_line
			(start 0.7874 0.4064)
			(end 0.7874 -0.4064)
			(stroke
				(width 0.1524)
				(type default)
			)
			(layer "B.SilkS")
		)
		(fp_line
			(start -0.7874 -0.4064)
			(end -0.7874 0.4064)
			(stroke
				(width 0.1524)
				(type default)
			)
			(layer "B.SilkS")
		)
		(fp_line
			(start 0.7874 -0.4064)
			(end -0.7874 -0.4064)
			(stroke
				(width 0.1524)
				(type default)
			)
			(layer "B.SilkS")
		)
		(fp_line
			(start -0.67945 0.3048)
			(end -0.120396 0.3048)
			(stroke
				(width 0.1)
				(type default)
			)
			(layer "B.Fab")
		)
		(fp_line
			(start -0.120396 0.3048)
			(end -0.120396 0.2794)
			(stroke
				(width 0.1)
				(type default)
			)
			(layer "B.Fab")
		)
		(fp_line
			(start 0.12065 0.3048)
			(end 0.67945 0.3048)
			(stroke
				(width 0.1)
				(type default)
			)
			(layer "B.Fab")
		)
		(fp_line
			(start 0.67945 0.3048)
			(end 0.67945 -0.305054)
			(stroke
				(width 0.1)
				(type default)
			)
			(layer "B.Fab")
		)
		(fp_line
			(start -0.120396 0.2794)
			(end 0.12065 0.2794)
			(stroke
				(width 0.1)
				(type default)
			)
			(layer "B.Fab")
		)
		(fp_line
			(start 0.12065 0.2794)
			(end 0.12065 0.3048)
			(stroke
				(width 0.1)
				(type default)
			)
			(layer "B.Fab")
		)
		(fp_line
			(start -0.12065 -0.2794)
			(end -0.12065 -0.3048)
			(stroke
				(width 0.1)
				(type default)
			)
			(layer "B.Fab")
		)
		(fp_line
			(start 0.12065 -0.2794)
			(end -0.12065 -0.2794)
			(stroke
				(width 0.1)
				(type default)
			)
			(layer "B.Fab")
		)
		(fp_line
			(start -0.67945 -0.3048)
			(end -0.67945 0.3048)
			(stroke
				(width 0.1)
				(type default)
			)
			(layer "B.Fab")
		)
		(fp_line
			(start -0.12065 -0.3048)
			(end -0.67945 -0.3048)
			(stroke
				(width 0.1)
				(type default)
			)
			(layer "B.Fab")
		)
		(fp_line
			(start 0.12065 -0.305054)
			(end 0.12065 -0.2794)
			(stroke
				(width 0.1)
				(type default)
			)
			(layer "B.Fab")
		)
		(fp_line
			(start 0.67945 -0.305054)
			(end 0.12065 -0.305054)
			(stroke
				(width 0.1)
				(type default)
			)
			(layer "B.Fab")
		)
		(pad "1" smd circle
			(at 0.40005 0 90)
			(size 0 0)
			(layers "B.Cu" "B.Mask" "B.Paste")
			(net "PVDDIO_P0_VOS1")
		)
		(pad "2" smd circle
			(at -0.40005 0 90)
			(size 0 0)
			(layers "B.Cu" "B.Mask" "B.Paste")
			(net "PVDDIO_P0")
		)
	)
	(footprint ""
		(layer "B.Cu")
		(at 159.7152 -191.1604 -90)
		(property "Reference" "R542"
			(at 0 0 90)
			(layer "B.SilkS")
			(hide yes)
			(effects
				(font
					(size 1.27 1.27)
				)
				(justify mirror)
			)
		)
		(property "Value" ""
			(at 0 0 90)
			(layer "B.Fab")
			(effects
				(font
					(size 1.27 1.27)
				)
				(justify mirror)
			)
		)
		(duplicate_pad_numbers_are_jumpers no)
		(fp_line
			(start -0.7874 0.4064)
			(end 0.7874 0.4064)
			(stroke
				(width 0.1524)
				(type default)
			)
			(layer "B.SilkS")
		)
		(fp_line
			(start 0.7874 0.4064)
			(end 0.7874 -0.4064)
			(stroke
				(width 0.1524)
				(type default)
			)
			(layer "B.SilkS")
		)
		(fp_line
			(start -0.7874 -0.4064)
			(end -0.7874 0.4064)
			(stroke
				(width 0.1524)
				(type default)
			)
			(layer "B.SilkS")
		)
		(fp_line
			(start 0.7874 -0.4064)
			(end -0.7874 -0.4064)
			(stroke
				(width 0.1524)
				(type default)
			)
			(layer "B.SilkS")
		)
		(fp_line
			(start -0.67945 0.3048)
			(end -0.120396 0.3048)
			(stroke
				(width 0.1)
				(type default)
			)
			(layer "B.Fab")
		)
		(fp_line
			(start -0.120396 0.3048)
			(end -0.120396 0.2794)
			(stroke
				(width 0.1)
				(type default)
			)
			(layer "B.Fab")
		)
		(fp_line
			(start 0.12065 0.3048)
			(end 0.67945 0.3048)
			(stroke
				(width 0.1)
				(type default)
			)
			(layer "B.Fab")
		)
		(fp_line
			(start 0.67945 0.3048)
			(end 0.67945 -0.305054)
			(stroke
				(width 0.1)
				(type default)
			)
			(layer "B.Fab")
		)
		(fp_line
			(start -0.120396 0.2794)
			(end 0.12065 0.2794)
			(stroke
				(width 0.1)
				(type default)
			)
			(layer "B.Fab")
		)
		(fp_line
			(start 0.12065 0.2794)
			(end 0.12065 0.3048)
			(stroke
				(width 0.1)
				(type default)
			)
			(layer "B.Fab")
		)
		(fp_line
			(start -0.12065 -0.2794)
			(end -0.12065 -0.3048)
			(stroke
				(width 0.1)
				(type default)
			)
			(layer "B.Fab")
		)
		(fp_line
			(start 0.12065 -0.2794)
			(end -0.12065 -0.2794)
			(stroke
				(width 0.1)
				(type default)
			)
			(layer "B.Fab")
		)
		(fp_line
			(start -0.67945 -0.3048)
			(end -0.67945 0.3048)
			(stroke
				(width 0.1)
				(type default)
			)
			(layer "B.Fab")
		)
		(fp_line
			(start -0.12065 -0.3048)
			(end -0.67945 -0.3048)
			(stroke
				(width 0.1)
				(type default)
			)
			(layer "B.Fab")
		)
		(fp_line
			(start 0.12065 -0.305054)
			(end 0.12065 -0.2794)
			(stroke
				(width 0.1)
				(type default)
			)
			(layer "B.Fab")
		)
		(fp_line
			(start 0.67945 -0.305054)
			(end 0.12065 -0.305054)
			(stroke
				(width 0.1)
				(type default)
			)
			(layer "B.Fab")
		)
		(pad "1" smd circle
			(at 0.40005 0 90)
			(size 0 0)
			(layers "B.Cu" "B.Mask" "B.Paste")
			(net "PVDD11_S3_P1")
		)
		(pad "2" smd circle
			(at -0.40005 0 90)
			(size 0 0)
			(layers "B.Cu" "B.Mask" "B.Paste")
			(net "I3C_1_SPD_DDRGL_CPU1_R_SCL")
		)
	)
	(footprint ""
		(layer "B.Cu")
		(at 446.644014 -192.660016)
		(property "Reference" "C169"
			(at 0 0 0)
			(layer "B.SilkS")
			(hide yes)
			(effects
				(font
					(size 1.27 1.27)
				)
				(justify mirror)
			)
		)
		(property "Value" ""
			(at 0 0 0)
			(layer "B.Fab")
			(effects
				(font
					(size 1.27 1.27)
				)
				(justify mirror)
			)
		)
		(duplicate_pad_numbers_are_jumpers no)
		(fp_line
			(start -1.524 -0.762)
			(end -1.524 0.762)
			(stroke
				(width 0.1524)
				(type default)
			)
			(layer "B.SilkS")
		)
		(fp_line
			(start -1.524 0.762)
			(end 1.524 0.762)
			(stroke
				(width 0.1524)
				(type default)
			)
			(layer "B.SilkS")
		)
		(fp_line
			(start 1.524 -0.762)
			(end -1.524 -0.762)
			(stroke
				(width 0.1524)
				(type default)
			)
			(layer "B.SilkS")
		)
		(fp_line
			(start 1.524 0.762)
			(end 1.524 -0.762)
			(stroke
				(width 0.1524)
				(type default)
			)
			(layer "B.SilkS")
		)
		(fp_line
			(start -1.1049 -0.724916)
			(end 1.1049 -0.724916)
			(stroke
				(width 0.1)
				(type default)
			)
			(layer "B.Fab")
		)
		(fp_line
			(start -1.1049 0.724916)
			(end -1.1049 -0.724916)
			(stroke
				(width 0.1)
				(type default)
			)
			(layer "B.Fab")
		)
		(fp_line
			(start 1.1049 -0.724916)
			(end 1.1049 0.724916)
			(stroke
				(width 0.1)
				(type default)
			)
			(layer "B.Fab")
		)
		(fp_line
			(start 1.1049 0.724916)
			(end -1.1049 0.724916)
			(stroke
				(width 0.1)
				(type default)
			)
			(layer "B.Fab")
		)
		(pad "1" smd rect
			(at 0.889 0)
			(size 1.016 1.27)
			(layers "B.Cu" "B.Mask" "B.Paste")
			(net "P12V_MEM_CPU0")
		)
		(pad "2" smd rect
			(at -0.889 0)
			(size 1.016 1.27)
			(layers "B.Cu" "B.Mask" "B.Paste")
			(net "GND")
		)
	)
)
